# S9S_MB_2U (Grand Teton) — schematic netlist excerpt (pin names and nets, part order shuffled) for the footprints in the layout excerpt that follows; sources: Cadence DE-HDL packaged netlist, KiCad conversion of 03242023_DA0F0TMBIJ0_F0T_Motherboard_J_brd_V01_OCP.brd

R2155  Q_RES  0 5% CHIP  pkg 0402LF  page 215 : A = FM_BMC_READY_R_PLD_N ; B = FM_BMC_READY_R_N
R3456  Q_RES  100K 1% EMPTY  pkg 0402LF  page 149 : A = P3V3_AUX ; B = GPU_BASE_STBY_EN_BUF_R

(kicad_pcb
	(version 20260206)
	(generator "pcbnew")
	(generator_version "10.0")
	(general
		(thickness 1.6)
		(legacy_teardrops no)
	)
	(paper "A4")
	(title_block
		(title "03242023_DA0F0TMBIJ0_F0T_Motherboard_J_brd_V01_OCP.brd")
		(comment 1 "Grand Teton / footprints 978-979 of 6105")
	)
	(layers
		(0 "F.Cu" signal "TOP")
		(4 "In1.Cu" signal "GND")
		(6 "In2.Cu" signal "IN1")
		(8 "In3.Cu" signal "GND1")
		(10 "In4.Cu" signal "IN2")
		(12 "In5.Cu" signal "GND2")
		(14 "In6.Cu" signal "IN3")
		(16 "In7.Cu" signal "GND3")
		(18 "In8.Cu" signal "VCC")
		(20 "In9.Cu" signal "VCC1")
		(22 "In10.Cu" signal "GND4")
		(24 "In11.Cu" signal "IN4")
		(26 "In12.Cu" signal "GND5")
		(28 "In13.Cu" signal "IN5")
		(30 "In14.Cu" signal "GND6")
		(32 "In15.Cu" signal "IN6")
		(34 "In16.Cu" signal "GND7")
		(2 "B.Cu" signal "BOTTOM")
		(9 "F.Adhes" user "F.Adhesive")
		(11 "B.Adhes" user "B.Adhesive")
		(13 "F.Paste" user "Package Geometry/Pastemask Top")
		(15 "B.Paste" user "Package Geometry/Pastemask Bottom")
		(5 "F.SilkS" user "Ref Des/Silkscreen Top")
		(7 "B.SilkS" user "Ref Des/Silkscreen Bottom")
		(1 "F.Mask" user "Board Geometry/Soldermask Top")
		(3 "B.Mask" user "Board Geometry/Soldermask Bottom")
		(17 "Dwgs.User" user "User.Drawings")
		(19 "Cmts.User" user "User.Comments")
		(21 "Eco1.User" user "User.Eco1")
		(23 "Eco2.User" user "User.Eco2")
		(25 "Edge.Cuts" user "Board Geometry/Outline")
		(27 "Margin" user)
		(31 "F.CrtYd" user "Package Geometry/Place Bound Top")
		(29 "B.CrtYd" user "Package Geometry/Place Bound Bottom")
		(35 "F.Fab" user "Ref Des/Assembly Top")
		(33 "B.Fab" user "Ref Des/Assembly Bottom")
	)
	(footprint ""
		(layer "F.Cu")
		(at 193.38036 -121.884948)
		(property "Reference" "R2155"
			(at 0 0 0)
			(layer "F.SilkS")
			(hide yes)
			(effects
				(font
					(size 1.27 1.27)
				)
			)
		)
		(property "Value" ""
			(at 0 0 0)
			(layer "F.Fab")
			(effects
				(font
					(size 1.27 1.27)
				)
			)
		)
		(duplicate_pad_numbers_are_jumpers no)
		(fp_line
			(start -0.7874 -0.4064)
			(end 0.7874 -0.4064)
			(stroke
				(width 0.1524)
				(type default)
			)
			(layer "F.SilkS")
		)
		(fp_line
			(start -0.7874 0.4064)
			(end -0.7874 -0.4064)
			(stroke
				(width 0.1524)
				(type default)
			)
			(layer "F.SilkS")
		)
		(fp_line
			(start 0.7874 -0.4064)
			(end 0.7874 0.4064)
			(stroke
				(width 0.1524)
				(type default)
			)
			(layer "F.SilkS")
		)
		(fp_line
			(start 0.7874 0.4064)
			(end -0.7874 0.4064)
			(stroke
				(width 0.1524)
				(type default)
			)
			(layer "F.SilkS")
		)
		(fp_line
			(start -0.67945 -0.305054)
			(end -0.12065 -0.305054)
			(stroke
				(width 0.1)
				(type default)
			)
			(layer "F.Fab")
		)
		(fp_line
			(start -0.67945 0.3048)
			(end -0.67945 -0.305054)
			(stroke
				(width 0.1)
				(type default)
			)
			(layer "F.Fab")
		)
		(fp_line
			(start -0.12065 -0.305054)
			(end -0.12065 -0.2794)
			(stroke
				(width 0.1)
				(type default)
			)
			(layer "F.Fab")
		)
		(fp_line
			(start -0.12065 -0.2794)
			(end 0.12065 -0.2794)
			(stroke
				(width 0.1)
				(type default)
			)
			(layer "F.Fab")
		)
		(fp_line
			(start -0.12065 0.2794)
			(end -0.12065 0.3048)
			(stroke
				(width 0.1)
				(type default)
			)
			(layer "F.Fab")
		)
		(fp_line
			(start -0.12065 0.3048)
			(end -0.67945 0.3048)
			(stroke
				(width 0.1)
				(type default)
			)
			(layer "F.Fab")
		)
		(fp_line
			(start 0.120396 0.2794)
			(end -0.12065 0.2794)
			(stroke
				(width 0.1)
				(type default)
			)
			(layer "F.Fab")
		)
		(fp_line
			(start 0.120396 0.3048)
			(end 0.120396 0.2794)
			(stroke
				(width 0.1)
				(type default)
			)
			(layer "F.Fab")
		)
		(fp_line
			(start 0.12065 -0.3048)
			(end 0.67945 -0.3048)
			(stroke
				(width 0.1)
				(type default)
			)
			(layer "F.Fab")
		)
		(fp_line
			(start 0.12065 -0.2794)
			(end 0.12065 -0.3048)
			(stroke
				(width 0.1)
				(type default)
			)
			(layer "F.Fab")
		)
		(fp_line
			(start 0.67945 -0.3048)
			(end 0.67945 0.3048)
			(stroke
				(width 0.1)
				(type default)
			)
			(layer "F.Fab")
		)
		(fp_line
			(start 0.67945 0.3048)
			(end 0.120396 0.3048)
			(stroke
				(width 0.1)
				(type default)
			)
			(layer "F.Fab")
		)
		(pad "1" smd circle
			(at -0.40005 0)
			(size 0 0)
			(layers "F.Cu" "F.Mask" "F.Paste")
			(net "FM_BMC_READY_R_PLD_N")
		)
		(pad "2" smd circle
			(at 0.40005 0)
			(size 0 0)
			(layers "F.Cu" "F.Mask" "F.Paste")
			(net "FM_BMC_READY_R_N")
		)
	)
	(footprint ""
		(layer "F.Cu")
		(at 170.23588 -434.939948 180)
		(property "Reference" "R3456"
			(at 0 0 180)
			(layer "F.SilkS")
			(hide yes)
			(effects
				(font
					(size 1.27 1.27)
				)
			)
		)
		(property "Value" ""
			(at 0 0 180)
			(layer "F.Fab")
			(effects
				(font
					(size 1.27 1.27)
				)
			)
		)
		(duplicate_pad_numbers_are_jumpers no)
		(fp_line
			(start 0.7874 0.4064)
			(end -0.7874 0.4064)
			(stroke
				(width 0.1524)
				(type default)
			)
			(layer "F.SilkS")
		)
		(fp_line
			(start 0.7874 -0.4064)
			(end 0.7874 0.4064)
			(stroke
				(width 0.1524)
				(type default)
			)
			(layer "F.SilkS")
		)
		(fp_line
			(start -0.7874 0.4064)
			(end -0.7874 -0.4064)
			(stroke
				(width 0.1524)
				(type default)
			)
			(layer "F.SilkS")
		)
		(fp_line
			(start -0.7874 -0.4064)
			(end 0.7874 -0.4064)
			(stroke
				(width 0.1524)
				(type default)
			)
			(layer "F.SilkS")
		)
		(fp_line
			(start 0.67945 0.3048)
			(end 0.120396 0.3048)
			(stroke
				(width 0.1)
				(type default)
			)
			(layer "F.Fab")
		)
		(fp_line
			(start 0.67945 -0.3048)
			(end 0.67945 0.3048)
			(stroke
				(width 0.1)
				(type default)
			)
			(layer "F.Fab")
		)
		(fp_line
			(start 0.12065 -0.2794)
			(end 0.12065 -0.3048)
			(stroke
				(width 0.1)
				(type default)
			)
			(layer "F.Fab")
		)
		(fp_line
			(start 0.12065 -0.3048)
			(end 0.67945 -0.3048)
			(stroke
				(width 0.1)
				(type default)
			)
			(layer "F.Fab")
		)
		(fp_line
			(start 0.120396 0.3048)
			(end 0.120396 0.2794)
			(stroke
				(width 0.1)
				(type default)
			)
			(layer "F.Fab")
		)
		(fp_line
			(start 0.120396 0.2794)
			(end -0.12065 0.2794)
			(stroke
				(width 0.1)
				(type default)
			)
			(layer "F.Fab")
		)
		(fp_line
			(start -0.12065 0.3048)
			(end -0.67945 0.3048)
			(stroke
				(width 0.1)
				(type default)
			)
			(layer "F.Fab")
		)
		(fp_line
			(start -0.12065 0.2794)
			(end -0.12065 0.3048)
			(stroke
				(width 0.1)
				(type default)
			)
			(layer "F.Fab")
		)
		(fp_line
			(start -0.12065 -0.2794)
			(end 0.12065 -0.2794)
			(stroke
				(width 0.1)
				(type default)
			)
			(layer "F.Fab")
		)
		(fp_line
			(start -0.12065 -0.305054)
			(end -0.12065 -0.2794)
			(stroke
				(width 0.1)
				(type default)
			)
			(layer "F.Fab")
		)
		(fp_line
			(start -0.67945 0.3048)
			(end -0.67945 -0.305054)
			(stroke
				(width 0.1)
				(type default)
			)
			(layer "F.Fab")
		)
		(fp_line
			(start -0.67945 -0.305054)
			(end -0.12065 -0.305054)
			(stroke
				(width 0.1)
				(type default)
			)
			(layer "F.Fab")
		)
		(pad "1" smd circle
			(at -0.40005 0 180)
			(size 0 0)
			(layers "F.Cu" "F.Mask" "F.Paste")
			(net "P3V3_AUX")
		)
		(pad "2" smd circle
			(at 0.40005 0 180)
			(size 0 0)
			(layers "F.Cu" "F.Mask" "F.Paste")
			(net "GPU_BASE_STBY_EN_BUF_R")
		)
	)
)
